(kicad_pcb
	(version 20260206)
	(generator "pcbnew")
	(generator_version "10.0")
	(general
		(thickness 1.6)
		(legacy_teardrops no)
	)
	(paper "A4")
	(title_block
		(title "04192023_DAF0TMB3IC0_F0TG_MB_C_brd_V02_OCP.brd")
		(comment 1 "Grand Teton / footprints 4845-4850 of 8354")
	)
	(layers
		(0 "F.Cu" signal "TOP")
		(4 "In1.Cu" signal "GND")
		(6 "In2.Cu" signal "IN1")
		(8 "In3.Cu" signal "GND1")
		(10 "In4.Cu" signal "IN2")
		(12 "In5.Cu" signal "GND2")
		(14 "In6.Cu" signal "IN3")
		(16 "In7.Cu" signal "GND3")
		(18 "In8.Cu" signal "VCC")
		(20 "In9.Cu" signal "VCC1")
		(22 "In10.Cu" signal "GND4")
		(24 "In11.Cu" signal "IN4")
		(26 "In12.Cu" signal "GND5")
		(28 "In13.Cu" signal "IN5")
		(30 "In14.Cu" signal "GND6")
		(32 "In15.Cu" signal "IN6")
		(34 "In16.Cu" signal "GND7")
		(2 "B.Cu" signal "BOTTOM")
		(9 "F.Adhes" user "F.Adhesive")
		(11 "B.Adhes" user "B.Adhesive")
		(13 "F.Paste" user "Package Geometry/Pastemask Top")
		(15 "B.Paste" user "Package Geometry/Pastemask Bottom")
		(5 "F.SilkS" user "Ref Des/Silkscreen Top")
		(7 "B.SilkS" user "Ref Des/Silkscreen Bottom")
		(1 "F.Mask" user "Board Geometry/Soldermask Top")
		(3 "B.Mask" user "Board Geometry/Soldermask Bottom")
		(17 "Dwgs.User" user "User.Drawings")
		(19 "Cmts.User" user "User.Comments")
		(21 "Eco1.User" user "User.Eco1")
		(23 "Eco2.User" user "User.Eco2")
		(25 "Edge.Cuts" user "Board Geometry/Outline")
		(27 "Margin" user)
		(31 "F.CrtYd" user "Package Geometry/Place Bound Top")
		(29 "B.CrtYd" user "Package Geometry/Place Bound Bottom")
		(35 "F.Fab" user "Ref Des/Assembly Top")
		(33 "B.Fab" user "Ref Des/Assembly Bottom")
	)
	(footprint ""
		(layer "F.Cu")
		(at 127.64897 -162.527234 -90)
		(property "Reference" "PC320"
			(at 0 0 270)
			(layer "F.SilkS")
			(hide yes)
			(effects
				(font
					(size 1.27 1.27)
				)
			)
		)
		(property "Value" ""
			(at 0 0 270)
			(layer "F.Fab")
			(effects
				(font
					(size 1.27 1.27)
				)
			)
		)
		(duplicate_pad_numbers_are_jumpers no)
		(fp_line
			(start -0.7874 0.4064)
			(end -0.7874 -0.4064)
			(stroke
				(width 0.1524)
				(type default)
			)
			(layer "F.SilkS")
		)
		(fp_line
			(start -0.286766 0.4064)
			(end -0.7874 0.4064)
			(stroke
				(width 0.1524)
				(type default)
			)
			(layer "F.SilkS")
		)
		(fp_line
			(start 0.7874 0.4064)
			(end 0.348234 0.4064)
			(stroke
				(width 0.1524)
				(type default)
			)
			(layer "F.SilkS")
		)
		(fp_line
			(start -0.7874 -0.4064)
			(end 0.7874 -0.4064)
			(stroke
				(width 0.1524)
				(type default)
			)
			(layer "F.SilkS")
		)
		(fp_line
			(start 0.7874 -0.4064)
			(end 0.7874 0.4064)
			(stroke
				(width 0.1524)
				(type default)
			)
			(layer "F.SilkS")
		)
		(fp_line
			(start -0.67945 0.3048)
			(end -0.67945 -0.305054)
			(stroke
				(width 0.1)
				(type default)
			)
			(layer "F.Fab")
		)
		(fp_line
			(start -0.12065 0.3048)
			(end -0.67945 0.3048)
			(stroke
				(width 0.1)
				(type default)
			)
			(layer "F.Fab")
		)
		(fp_line
			(start 0.120396 0.3048)
			(end 0.120396 0.2794)
			(stroke
				(width 0.1)
				(type default)
			)
			(layer "F.Fab")
		)
		(fp_line
			(start 0.67945 0.3048)
			(end 0.120396 0.3048)
			(stroke
				(width 0.1)
				(type default)
			)
			(layer "F.Fab")
		)
		(fp_line
			(start -0.12065 0.2794)
			(end -0.12065 0.3048)
			(stroke
				(width 0.1)
				(type default)
			)
			(layer "F.Fab")
		)
		(fp_line
			(start 0.120396 0.2794)
			(end -0.12065 0.2794)
			(stroke
				(width 0.1)
				(type default)
			)
			(layer "F.Fab")
		)
		(fp_line
			(start -0.12065 -0.2794)
			(end 0.12065 -0.2794)
			(stroke
				(width 0.1)
				(type default)
			)
			(layer "F.Fab")
		)
		(fp_line
			(start 0.12065 -0.2794)
			(end 0.12065 -0.3048)
			(stroke
				(width 0.1)
				(type default)
			)
			(layer "F.Fab")
		)
		(fp_line
			(start 0.12065 -0.3048)
			(end 0.67945 -0.3048)
			(stroke
				(width 0.1)
				(type default)
			)
			(layer "F.Fab")
		)
		(fp_line
			(start 0.67945 -0.3048)
			(end 0.67945 0.3048)
			(stroke
				(width 0.1)
				(type default)
			)
			(layer "F.Fab")
		)
		(fp_line
			(start -0.67945 -0.305054)
			(end -0.12065 -0.305054)
			(stroke
				(width 0.1)
				(type default)
			)
			(layer "F.Fab")
		)
		(fp_line
			(start -0.12065 -0.305054)
			(end -0.12065 -0.2794)
			(stroke
				(width 0.1)
				(type default)
			)
			(layer "F.Fab")
		)
		(pad "1" smd circle
			(at -0.40005 0 270)
			(size 0 0)
			(layers "F.Cu" "F.Mask" "F.Paste")
			(net "PVDDCR_SOC_P1_VCC2")
		)
		(pad "2" smd circle
			(at 0.40005 0 270)
			(size 0 0)
			(layers "F.Cu" "F.Mask" "F.Paste")
			(net "GND")
		)
	)
	(footprint ""
		(layer "F.Cu")
		(at 254.592836 -126.91745)
		(property "Reference" "R3708"
			(at 0 0 0)
			(layer "F.SilkS")
			(hide yes)
			(effects
				(font
					(size 1.27 1.27)
				)
			)
		)
		(property "Value" ""
			(at 0 0 0)
			(layer "F.Fab")
			(effects
				(font
					(size 1.27 1.27)
				)
			)
		)
		(duplicate_pad_numbers_are_jumpers no)
		(fp_line
			(start -0.7874 -0.4064)
			(end 0.7874 -0.4064)
			(stroke
				(width 0.1524)
				(type default)
			)
			(layer "F.SilkS")
		)
		(fp_line
			(start -0.7874 0.4064)
			(end -0.7874 -0.4064)
			(stroke
				(width 0.1524)
				(type default)
			)
			(layer "F.SilkS")
		)
		(fp_line
			(start 0.7874 -0.4064)
			(end 0.7874 0.4064)
			(stroke
				(width 0.1524)
				(type default)
			)
			(layer "F.SilkS")
		)
		(fp_line
			(start 0.7874 0.4064)
			(end -0.7874 0.4064)
			(stroke
				(width 0.1524)
				(type default)
			)
			(layer "F.SilkS")
		)
		(fp_line
			(start -0.67945 -0.305054)
			(end -0.12065 -0.305054)
			(stroke
				(width 0.1)
				(type default)
			)
			(layer "F.Fab")
		)
		(fp_line
			(start -0.67945 0.3048)
			(end -0.67945 -0.305054)
			(stroke
				(width 0.1)
				(type default)
			)
			(layer "F.Fab")
		)
		(fp_line
			(start -0.12065 -0.305054)
			(end -0.12065 -0.2794)
			(stroke
				(width 0.1)
				(type default)
			)
			(layer "F.Fab")
		)
		(fp_line
			(start -0.12065 -0.2794)
			(end 0.12065 -0.2794)
			(stroke
				(width 0.1)
				(type default)
			)
			(layer "F.Fab")
		)
		(fp_line
			(start -0.12065 0.2794)
			(end -0.12065 0.3048)
			(stroke
				(width 0.1)
				(type default)
			)
			(layer "F.Fab")
		)
		(fp_line
			(start -0.12065 0.3048)
			(end -0.67945 0.3048)
			(stroke
				(width 0.1)
				(type default)
			)
			(layer "F.Fab")
		)
		(fp_line
			(start 0.120396 0.2794)
			(end -0.12065 0.2794)
			(stroke
				(width 0.1)
				(type default)
			)
			(layer "F.Fab")
		)
		(fp_line
			(start 0.120396 0.3048)
			(end 0.120396 0.2794)
			(stroke
				(width 0.1)
				(type default)
			)
			(layer "F.Fab")
		)
		(fp_line
			(start 0.12065 -0.3048)
			(end 0.67945 -0.3048)
			(stroke
				(width 0.1)
				(type default)
			)
			(layer "F.Fab")
		)
		(fp_line
			(start 0.12065 -0.2794)
			(end 0.12065 -0.3048)
			(stroke
				(width 0.1)
				(type default)
			)
			(layer "F.Fab")
		)
		(fp_line
			(start 0.67945 -0.3048)
			(end 0.67945 0.3048)
			(stroke
				(width 0.1)
				(type default)
			)
			(layer "F.Fab")
		)
		(fp_line
			(start 0.67945 0.3048)
			(end 0.120396 0.3048)
			(stroke
				(width 0.1)
				(type default)
			)
			(layer "F.Fab")
		)
		(pad "1" smd circle
			(at -0.40005 0)
			(size 0 0)
			(layers "F.Cu" "F.Mask" "F.Paste")
			(net "P3V3_AUX")
		)
		(pad "2" smd circle
			(at 0.40005 0)
			(size 0 0)
			(layers "F.Cu" "F.Mask" "F.Paste")
			(net "PCA9548_PCIE0_ADDR0")
		)
	)
	(footprint ""
		(layer "F.Cu")
		(at 234.739688 -148.948648 180)
		(property "Reference" "U153"
			(at -3.725164 -3.332988 0)
			(unlocked yes)
			(layer "F.SilkS")
			(effects
				(font
					(size 0.7874 0.5842)
					(thickness 0.1524)
				)
				(justify left)
			)
		)
		(property "Value" ""
			(at 0 0 180)
			(layer "F.Fab")
			(effects
				(font
					(size 1.27 1.27)
				)
			)
		)
		(duplicate_pad_numbers_are_jumpers no)
		(fp_line
			(start 1.0414 1.575054)
			(end -1.0414 1.575054)
			(stroke
				(width 0.1524)
				(type default)
			)
			(layer "F.SilkS")
		)
		(fp_line
			(start 1.0414 -1.575054)
			(end 1.0414 1.575054)
			(stroke
				(width 0.1524)
				(type default)
			)
			(layer "F.SilkS")
		)
		(fp_line
			(start 0.254 -1.575054)
			(end 1.0414 -1.575054)
			(stroke
				(width 0.1524)
				(type default)
			)
			(layer "F.SilkS")
		)
		(fp_line
			(start 0.2286 -1.575054)
			(end 0 -1.272032)
			(stroke
				(width 0.1524)
				(type default)
			)
			(layer "F.SilkS")
		)
		(fp_line
			(start 0 -1.272032)
			(end -0.254 -1.575054)
			(stroke
				(width 0.1524)
				(type default)
			)
			(layer "F.SilkS")
		)
		(fp_line
			(start -1.0414 1.575054)
			(end -1.0414 -1.575054)
			(stroke
				(width 0.1524)
				(type default)
			)
			(layer "F.SilkS")
		)
		(fp_line
			(start -1.0414 -1.575054)
			(end -0.254 -1.575054)
			(stroke
				(width 0.1524)
				(type default)
			)
			(layer "F.SilkS")
		)
		(fp_poly
			(pts
				(xy -3.960876 -2.091182) (xy -3.242564 -2.809748) (xy -2.883154 -1.732026)
			)
			(stroke
				(width 0)
				(type default)
			)
			(fill yes)
			(layer "F.SilkS")
		)
		(fp_line
			(start 2.5654 1.2192)
			(end 1.4478 1.2192)
			(stroke
				(width 0.1)
				(type default)
			)
			(layer "F.Fab")
		)
		(fp_line
			(start 2.5654 -1.2192)
			(end 2.5654 1.2192)
			(stroke
				(width 0.1)
				(type default)
			)
			(layer "F.Fab")
		)
		(fp_line
			(start 1.4478 1.5748)
			(end -1.4478 1.5748)
			(stroke
				(width 0.1)
				(type default)
			)
			(layer "F.Fab")
		)
		(fp_line
			(start 1.4478 1.2192)
			(end 1.4478 1.5748)
			(stroke
				(width 0.1)
				(type default)
			)
			(layer "F.Fab")
		)
		(fp_line
			(start 1.4478 -1.2192)
			(end 2.5654 -1.2192)
			(stroke
				(width 0.1)
				(type default)
			)
			(layer "F.Fab")
		)
		(fp_line
			(start 1.4478 -1.5748)
			(end 1.4478 -1.2192)
			(stroke
				(width 0.1)
				(type default)
			)
			(layer "F.Fab")
		)
		(fp_line
			(start -1.4478 1.5748)
			(end -1.4478 1.2192)
			(stroke
				(width 0.1)
				(type default)
			)
			(layer "F.Fab")
		)
		(fp_line
			(start -1.4478 1.2192)
			(end -2.5654 1.2192)
			(stroke
				(width 0.1)
				(type default)
			)
			(layer "F.Fab")
		)
		(fp_line
			(start -1.4478 -1.2192)
			(end -1.4478 -1.5748)
			(stroke
				(width 0.1)
				(type default)
			)
			(layer "F.Fab")
		)
		(fp_line
			(start -1.4478 -1.5748)
			(end 1.4478 -1.5748)
			(stroke
				(width 0.1)
				(type default)
			)
			(layer "F.Fab")
		)
		(fp_line
			(start -2.5654 1.2192)
			(end -2.5654 -1.2192)
			(stroke
				(width 0.1)
				(type default)
			)
			(layer "F.Fab")
		)
		(fp_line
			(start -2.5654 -1.2192)
			(end -1.4478 -1.2192)
			(stroke
				(width 0.1)
				(type default)
			)
			(layer "F.Fab")
		)
		(fp_poly
			(pts
				(xy -2.710688 -0.975106) (xy -3.726688 -1.483106) (xy -3.726688 -0.467106)
			)
			(stroke
				(width 0)
				(type default)
			)
			(fill yes)
			(layer "F.Fab")
		)
		(pad "1" smd rect
			(at -1.849882 -0.975106 90)
			(size 0.3556 1.3208)
			(layers "F.Cu" "F.Mask" "F.Paste")
			(net "JTAG_CPUX_TDI")
		)
		(pad "2" smd rect
			(at -1.849882 -0.32512 90)
			(size 0.3556 1.3208)
			(layers "F.Cu" "F.Mask" "F.Paste")
			(net "JTAG_CPU0_R_TDI")
		)
		(pad "3" smd rect
			(at -1.849882 0.32512 90)
			(size 0.3556 1.3208)
			(layers "F.Cu" "F.Mask" "F.Paste")
			(net "FM_PLD_CPU0_PRSNT_HDT_N")
		)
		(pad "4" smd rect
			(at -1.849882 0.975106 90)
			(size 0.3556 1.3208)
			(layers "F.Cu" "F.Mask" "F.Paste")
			(net "GND")
		)
		(pad "5" smd rect
			(at 1.849882 0.975106 90)
			(size 0.3556 1.3208)
			(layers "F.Cu" "F.Mask" "F.Paste")
			(net "JTAG_CPUX_TDI")
		)
		(pad "6" smd rect
			(at 1.849882 0.32512 90)
			(size 0.3556 1.3208)
			(layers "F.Cu" "F.Mask" "F.Paste")
			(net "JTAG_CPU0_BYPASS")
		)
		(pad "7" smd rect
			(at 1.849882 -0.32512 90)
			(size 0.3556 1.3208)
			(layers "F.Cu" "F.Mask" "F.Paste")
			(net "CPU0_HDT_BYPASS_SEL")
		)
		(pad "8" smd rect
			(at 1.849882 -0.975106 90)
			(size 0.3556 1.3208)
			(layers "F.Cu" "F.Mask" "F.Paste")
			(net "PVDD18_S5_P0")
		)
	)
	(footprint ""
		(layer "F.Cu")
		(at 163.59632 -102.00132 180)
		(property "Reference" "R6188"
			(at 0 0 180)
			(layer "F.SilkS")
			(hide yes)
			(effects
				(font
					(size 1.27 1.27)
				)
			)
		)
		(property "Value" ""
			(at 0 0 180)
			(layer "F.Fab")
			(effects
				(font
					(size 1.27 1.27)
				)
			)
		)
		(duplicate_pad_numbers_are_jumpers no)
		(fp_line
			(start 0.7874 0.4064)
			(end -0.7874 0.4064)
			(stroke
				(width 0.1524)
				(type default)
			)
			(layer "F.SilkS")
		)
		(fp_line
			(start 0.7874 -0.4064)
			(end 0.7874 0.4064)
			(stroke
				(width 0.1524)
				(type default)
			)
			(layer "F.SilkS")
		)
		(fp_line
			(start -0.7874 0.4064)
			(end -0.7874 -0.4064)
			(stroke
				(width 0.1524)
				(type default)
			)
			(layer "F.SilkS")
		)
		(fp_line
			(start -0.7874 -0.4064)
			(end 0.7874 -0.4064)
			(stroke
				(width 0.1524)
				(type default)
			)
			(layer "F.SilkS")
		)
		(fp_line
			(start 0.67945 0.3048)
			(end 0.120396 0.3048)
			(stroke
				(width 0.1)
				(type default)
			)
			(layer "F.Fab")
		)
		(fp_line
			(start 0.67945 -0.3048)
			(end 0.67945 0.3048)
			(stroke
				(width 0.1)
				(type default)
			)
			(layer "F.Fab")
		)
		(fp_line
			(start 0.12065 -0.2794)
			(end 0.12065 -0.3048)
			(stroke
				(width 0.1)
				(type default)
			)
			(layer "F.Fab")
		)
		(fp_line
			(start 0.12065 -0.3048)
			(end 0.67945 -0.3048)
			(stroke
				(width 0.1)
				(type default)
			)
			(layer "F.Fab")
		)
		(fp_line
			(start 0.120396 0.3048)
			(end 0.120396 0.2794)
			(stroke
				(width 0.1)
				(type default)
			)
			(layer "F.Fab")
		)
		(fp_line
			(start 0.120396 0.2794)
			(end -0.12065 0.2794)
			(stroke
				(width 0.1)
				(type default)
			)
			(layer "F.Fab")
		)
		(fp_line
			(start -0.12065 0.3048)
			(end -0.67945 0.3048)
			(stroke
				(width 0.1)
				(type default)
			)
			(layer "F.Fab")
		)
		(fp_line
			(start -0.12065 0.2794)
			(end -0.12065 0.3048)
			(stroke
				(width 0.1)
				(type default)
			)
			(layer "F.Fab")
		)
		(fp_line
			(start -0.12065 -0.2794)
			(end 0.12065 -0.2794)
			(stroke
				(width 0.1)
				(type default)
			)
			(layer "F.Fab")
		)
		(fp_line
			(start -0.12065 -0.305054)
			(end -0.12065 -0.2794)
			(stroke
				(width 0.1)
				(type default)
			)
			(layer "F.Fab")
		)
		(fp_line
			(start -0.67945 0.3048)
			(end -0.67945 -0.305054)
			(stroke
				(width 0.1)
				(type default)
			)
			(layer "F.Fab")
		)
		(fp_line
			(start -0.67945 -0.305054)
			(end -0.12065 -0.305054)
			(stroke
				(width 0.1)
				(type default)
			)
			(layer "F.Fab")
		)
		(pad "1" smd circle
			(at -0.40005 0 180)
			(size 0 0)
			(layers "F.Cu" "F.Mask" "F.Paste")
			(net "FM_SEC_MUX_SEL")
		)
		(pad "2" smd circle
			(at 0.40005 0 180)
			(size 0 0)
			(layers "F.Cu" "F.Mask" "F.Paste")
			(net "P3V3_AUX")
		)
	)
	(footprint ""
		(layer "F.Cu")
		(at 300.691296 -378.95403 -90)
		(property "Reference" "C927"
			(at 0 0 270)
			(layer "F.SilkS")
			(hide yes)
			(effects
				(font
					(size 1.27 1.27)
				)
			)
		)
		(property "Value" ""
			(at 0 0 270)
			(layer "F.Fab")
			(effects
				(font
					(size 1.27 1.27)
				)
			)
		)
		(duplicate_pad_numbers_are_jumpers no)
		(fp_line
			(start -0.299974 0.150114)
			(end -0.299974 -0.150114)
			(stroke
				(width 0.1)
				(type default)
			)
			(layer "F.Fab")
		)
		(fp_line
			(start 0.299974 0.150114)
			(end -0.299974 0.150114)
			(stroke
				(width 0.1)
				(type default)
			)
			(layer "F.Fab")
		)
		(fp_line
			(start -0.299974 -0.150114)
			(end 0.299974 -0.150114)
			(stroke
				(width 0.1)
				(type default)
			)
			(layer "F.Fab")
		)
		(fp_line
			(start 0.299974 -0.150114)
			(end 0.299974 0.150114)
			(stroke
				(width 0.1)
				(type default)
			)
			(layer "F.Fab")
		)
		(pad "1" smd rect
			(at -0.2667 0 270)
			(size 0.3048 0.381)
			(layers "F.Cu" "F.Mask" "F.Paste")
			(net "P5E_CPU0_P0_TX_C_DP<3>")
		)
		(pad "2" smd rect
			(at 0.2667 0 270)
			(size 0.3048 0.381)
			(layers "F.Cu" "F.Mask" "F.Paste")
			(net "P5E_CPU0_P0_TX_DP<3>")
		)
	)
	(footprint ""
		(layer "F.Cu")
		(at 418.253164 -16.100298 90)
		(property "Reference" "C1568"
			(at 0 0 90)
			(layer "F.SilkS")
			(hide yes)
			(effects
				(font
					(size 1.27 1.27)
				)
			)
		)
		(property "Value" ""
			(at 0 0 90)
			(layer "F.Fab")
			(effects
				(font
					(size 1.27 1.27)
				)
			)
		)
		(duplicate_pad_numbers_are_jumpers no)
		(fp_line
			(start 0.299974 -0.150114)
			(end 0.299974 0.150114)
			(stroke
				(width 0.1)
				(type default)
			)
			(layer "F.Fab")
		)
		(fp_line
			(start -0.299974 -0.150114)
			(end 0.299974 -0.150114)
			(stroke
				(width 0.1)
				(type default)
			)
			(layer "F.Fab")
		)
		(fp_line
			(start 0.299974 0.150114)
			(end -0.299974 0.150114)
			(stroke
				(width 0.1)
				(type default)
			)
			(layer "F.Fab")
		)
		(fp_line
			(start -0.299974 0.150114)
			(end -0.299974 -0.150114)
			(stroke
				(width 0.1)
				(type default)
			)
			(layer "F.Fab")
		)
		(pad "1" smd rect
			(at -0.2667 0 90)
			(size 0.3048 0.381)
			(layers "F.Cu" "F.Mask" "F.Paste")
			(net "P5E_CPU0_G3_TX_C_DN<5>")
		)
		(pad "2" smd rect
			(at 0.2667 0 90)
			(size 0.3048 0.381)
			(layers "F.Cu" "F.Mask" "F.Paste")
			(net "P5E_CPU0_G3_TX_DN<5>")
		)
	)
)
